(kicad_pcb
	(version 20241229)
	(generator "pcbnew")
	(generator_version "9.0")
	(general
		(thickness 1.6642)
		(legacy_teardrops no)
	)
	(paper "A3")
	(title_block
		(title "PolarFire SoM")
		(date "2025-07-22")
		(rev "1.1.4")
		(company "Antmicro Ltd")
		(comment 1 "www.antmicro.com")
		(comment 9 "footprints 374-377 of 470")
	)
	(layers
		(0 "F.Cu" mixed)
		(4 "In1.Cu" power)
		(6 "In2.Cu" signal)
		(8 "In3.Cu" power)
		(10 "In4.Cu" signal)
		(12 "In5.Cu" power)
		(14 "In6.Cu" power)
		(16 "In7.Cu" signal)
		(18 "In8.Cu" power)
		(20 "In9.Cu" signal)
		(22 "In10.Cu" power)
		(24 "In11.Cu" signal)
		(26 "In12.Cu" signal)
		(2 "B.Cu" mixed)
		(9 "F.Adhes" user "F.Adhesive")
		(11 "B.Adhes" user "B.Adhesive")
		(13 "F.Paste" user)
		(15 "B.Paste" user)
		(5 "F.SilkS" user "F.Silkscreen")
		(7 "B.SilkS" user "B.Silkscreen")
		(1 "F.Mask" user)
		(3 "B.Mask" user)
		(17 "Dwgs.User" user "User.Drawings")
		(19 "Cmts.User" user "User.Comments")
		(21 "Eco1.User" user "User.Eco1")
		(23 "Eco2.User" user "User.Eco2")
		(25 "Edge.Cuts" user)
		(27 "Margin" user)
		(31 "F.CrtYd" user "F.Courtyard")
		(29 "B.CrtYd" user "B.Courtyard")
		(35 "F.Fab" user)
		(33 "B.Fab" user)
	)
	(footprint "antmicro-footprints:R_Array_4x0201_Panasonic_EXB18V"
		(layer "B.Cu")
		(at 203.24884 121.65 -90)
		(property "Reference" "R23"
			(at 1.15 -1.50116 90)
			(layer "B.SilkS")
			(effects
				(font
					(size 0.7 0.7)
					(thickness 0.15)
				)
				(justify right bottom mirror)
			)
		)
		(property "Value" "R_4x0R_0201_array"
			(at -1.1 -1.8 90)
			(layer "B.Fab")
			(hide yes)
			(effects
				(font
					(size 0.7 0.7)
					(thickness 0.15)
				)
				(justify left bottom mirror)
			)
		)
		(property "Datasheet" "http://industrial.panasonic.com/cdbs/www-data/pdf/AOC0000/AOC0000C14.pdf"
			(at 0 0 270)
			(layer "F.Fab")
			(hide yes)
			(effects
				(font
					(size 1.27 1.27)
					(thickness 0.15)
				)
			)
		)
		(property "Description" "Zero Ohm Network Resistor, Jumper, 0201 [0603 Metric], Thick Film, Isolated, Flat, 4 Resistors"
			(at 0 0 270)
			(layer "F.Fab")
			(hide yes)
			(effects
				(font
					(size 1.27 1.27)
					(thickness 0.15)
				)
			)
		)
		(property "Author" "Antmicro"
			(at 81.59884 324.89884 0)
			(layer "B.Fab")
			(hide yes)
			(effects
				(font
					(size 1 1)
					(thickness 0.15)
				)
				(justify mirror)
			)
		)
		(property "License" "Apache-2.0"
			(at 81.59884 324.89884 0)
			(layer "B.Fab")
			(hide yes)
			(effects
				(font
					(size 1 1)
					(thickness 0.15)
				)
				(justify mirror)
			)
		)
		(property "MPN" "EXB-18VR000X"
			(at 81.59884 324.89884 0)
			(layer "B.Fab")
			(hide yes)
			(effects
				(font
					(size 1 1)
					(thickness 0.15)
				)
				(justify mirror)
			)
		)
		(property "Manufacturer" "Panasonic"
			(at 81.59884 324.89884 0)
			(layer "B.Fab")
			(hide yes)
			(effects
				(font
					(size 1 1)
					(thickness 0.15)
				)
				(justify mirror)
			)
		)
		(property "Val" "4x0R_0201"
			(at 81.59884 324.89884 0)
			(layer "B.Fab")
			(hide yes)
			(effects
				(font
					(size 1 1)
					(thickness 0.15)
				)
				(justify mirror)
			)
		)
		(sheetname "/FPGA MSSIO/")
		(sheetfile "fpga-mssio.kicad_sch")
		(attr smd)
		(fp_line
			(start -0.8 0.45)
			(end -0.8 -0.45)
			(stroke
				(width 0.12)
				(type solid)
			)
			(layer "B.SilkS")
		)
		(fp_line
			(start 0.8 0.45)
			(end 0.8 -0.45)
			(stroke
				(width 0.12)
				(type solid)
			)
			(layer "B.SilkS")
		)
		(fp_rect
			(start -0.898 0.66)
			(end 0.898 -0.65)
			(stroke
				(width 0.05)
				(type solid)
			)
			(fill no)
			(layer "B.CrtYd")
		)
		(fp_text user "Author: Antmicro"
			(at -1.051 -4.599 90)
			(layer "B.Fab")
			(effects
				(font
					(size 0.7 0.7)
					(thickness 0.15)
				)
				(justify left bottom mirror)
			)
		)
		(fp_text user "${REFERENCE}"
			(at -1.051 -3.2 90)
			(layer "B.Fab")
			(effects
				(font
					(size 0.7 0.7)
					(thickness 0.15)
				)
				(justify left bottom mirror)
			)
		)
		(fp_text user "License: Apache-2.0"
			(at -1.051 -6 90)
			(layer "B.Fab")
			(effects
				(font
					(size 0.7 0.7)
					(thickness 0.15)
				)
				(justify left bottom mirror)
			)
		)
		(pad "1" smd roundrect
			(at -0.6 -0.298 270)
			(size 0.2 0.4)
			(layers "B.Cu" "B.Mask" "B.Paste")
			(roundrect_rratio 0.25)
			(net 243 "/FPGA MSSIO/EMMC.DAT1")
			(pinfunction "R1.1")
			(pintype "passive")
		)
		(pad "2" smd roundrect
			(at -0.202 -0.298 270)
			(size 0.2 0.4)
			(layers "B.Cu" "B.Mask" "B.Paste")
			(roundrect_rratio 0.25)
			(net 248 "/FPGA MSSIO/EMMC.DAT2")
			(pinfunction "R2.1")
			(pintype "passive")
		)
		(pad "3" smd roundrect
			(at 0.2 -0.298 270)
			(size 0.2 0.4)
			(layers "B.Cu" "B.Mask" "B.Paste")
			(roundrect_rratio 0.25)
			(net 249 "/FPGA MSSIO/EMMC.DAT6")
			(pinfunction "R3.1")
			(pintype "passive")
		)
		(pad "4" smd roundrect
			(at 0.598 -0.298 270)
			(size 0.2 0.4)
			(layers "B.Cu" "B.Mask" "B.Paste")
			(roundrect_rratio 0.25)
			(net 250 "/FPGA MSSIO/EMMC.DAT4")
			(pinfunction "R4.1")
			(pintype "passive")
		)
		(pad "5" smd roundrect
			(at 0.598 0.3 270)
			(size 0.2 0.4)
			(layers "B.Cu" "B.Mask" "B.Paste")
			(roundrect_rratio 0.25)
			(net 251 "/FPGA MSSIO/MEM.DAT4")
			(pinfunction "R4.2")
			(pintype "passive")
		)
		(pad "6" smd roundrect
			(at 0.2 0.3 270)
			(size 0.2 0.4)
			(layers "B.Cu" "B.Mask" "B.Paste")
			(roundrect_rratio 0.25)
			(net 252 "/FPGA MSSIO/MEM.DAT6")
			(pinfunction "R3.2")
			(pintype "passive")
		)
		(pad "7" smd roundrect
			(at -0.202 0.3 270)
			(size 0.2 0.4)
			(layers "B.Cu" "B.Mask" "B.Paste")
			(roundrect_rratio 0.25)
			(net 261 "/FPGA MSSIO/MEM.DAT2")
			(pinfunction "R2.2")
			(pintype "passive")
		)
		(pad "8" smd roundrect
			(at -0.6 0.3 270)
			(size 0.2 0.4)
			(layers "B.Cu" "B.Mask" "B.Paste")
			(roundrect_rratio 0.25)
			(net 262 "/FPGA MSSIO/MEM.DAT1")
			(pinfunction "R1.2")
			(pintype "passive")
		)
	)
	(footprint "antmicro-footprints:R_0402_1005Metric"
		(layer "B.Cu")
		(at 177.75 145.46 -90)
		(descr "Resistor SMD 0402")
		(tags "resistor SMD 0402")
		(property "Reference" "R94"
			(at 0.885 -1.36 90)
			(layer "B.SilkS")
			(effects
				(font
					(size 0.7 0.7)
					(thickness 0.15)
				)
				(justify left bottom mirror)
			)
		)
		(property "Value" "R_0R_0402"
			(at -1.011843 -1.772047 90)
			(layer "B.Fab")
			(hide yes)
			(effects
				(font
					(size 0.7 0.7)
					(thickness 0.15)
				)
				(justify left bottom mirror)
			)
		)
		(property "Datasheet" "https://industrial.panasonic.com/cdbs/www-data/pdf/RDA0000/AOA0000C301.pdf"
			(at 0 0 270)
			(layer "F.Fab")
			(hide yes)
			(effects
				(font
					(size 1.27 1.27)
					(thickness 0.15)
				)
			)
		)
		(property "Description" "SMD Chip Resistor, Jumper, 0 ohm, 100 mW, 0402 [1005 Metric], Thick Film, General Purpose"
			(at 0 0 270)
			(layer "F.Fab")
			(hide yes)
			(effects
				(font
					(size 1.27 1.27)
					(thickness 0.15)
				)
			)
		)
		(property "Author" "Antmicro"
			(at 32.29 323.21 0)
			(layer "B.Fab")
			(hide yes)
			(effects
				(font
					(size 1 1)
					(thickness 0.15)
				)
				(justify mirror)
			)
		)
		(property "Current" "1A"
			(at 32.29 323.21 0)
			(layer "B.Fab")
			(hide yes)
			(effects
				(font
					(size 1 1)
					(thickness 0.15)
				)
				(justify mirror)
			)
		)
		(property "License" "Apache-2.0"
			(at 32.29 323.21 0)
			(layer "B.Fab")
			(hide yes)
			(effects
				(font
					(size 1 1)
					(thickness 0.15)
				)
				(justify mirror)
			)
		)
		(property "MPN" "ERJ2GE0R00X"
			(at 32.29 323.21 0)
			(layer "B.Fab")
			(hide yes)
			(effects
				(font
					(size 1 1)
					(thickness 0.15)
				)
				(justify mirror)
			)
		)
		(property "Manufacturer" "Panasonic"
			(at 32.29 323.21 0)
			(layer "B.Fab")
			(hide yes)
			(effects
				(font
					(size 1 1)
					(thickness 0.15)
				)
				(justify mirror)
			)
		)
		(property "Public" ""
			(at 32.29 323.21 0)
			(layer "B.Fab")
			(hide yes)
			(effects
				(font
					(size 1 1)
					(thickness 0.15)
				)
				(justify mirror)
			)
		)
		(property "Tolerance" "~"
			(at 32.29 323.21 0)
			(layer "B.Fab")
			(hide yes)
			(effects
				(font
					(size 1 1)
					(thickness 0.15)
				)
				(justify mirror)
			)
		)
		(property "Val" "0R"
			(at 32.29 323.21 0)
			(layer "B.Fab")
			(hide yes)
			(effects
				(font
					(size 1 1)
					(thickness 0.15)
				)
				(justify mirror)
			)
		)
		(sheetname "/Supply/")
		(sheetfile "supply.kicad_sch")
		(attr smd)
		(fp_rect
			(start -0.925 0.47)
			(end 0.925 -0.47)
			(stroke
				(width 0.05)
				(type default)
			)
			(fill no)
			(layer "B.CrtYd")
		)
		(fp_rect
			(start -0.5 0.25)
			(end 0.5 -0.25)
			(stroke
				(width 0.15)
				(type solid)
			)
			(fill no)
			(layer "B.Fab")
		)
		(fp_text user "License: Apache-2.0"
			(at -0.95 -5.169 90)
			(layer "B.Fab")
			(effects
				(font
					(size 0.7 0.7)
					(thickness 0.15)
				)
				(justify left bottom mirror)
			)
		)
		(fp_text user "${REFERENCE}"
			(at -0.95 -3.168 90)
			(layer "B.Fab")
			(effects
				(font
					(size 0.7 0.7)
					(thickness 0.15)
				)
				(justify left bottom mirror)
			)
		)
		(fp_text user "Author: Antmicro"
			(at -0.95 -4.169 90)
			(layer "B.Fab")
			(effects
				(font
					(size 0.7 0.7)
					(thickness 0.15)
				)
				(justify left bottom mirror)
			)
		)
		(pad "1" smd roundrect
			(at -0.48 0 270)
			(size 0.59 0.64)
			(layers "B.Cu" "B.Mask" "B.Paste")
			(roundrect_rratio 0.25)
			(net 406 "/Supply/SENSE2_P")
			(pintype "passive")
		)
		(pad "2" smd roundrect
			(at 0.48 0 270)
			(size 0.59 0.64)
			(layers "B.Cu" "B.Mask" "B.Paste")
			(roundrect_rratio 0.25)
			(net 577 "Net-(U6-SENSE2+)")
			(pintype "passive")
		)
	)
	(footprint "antmicro-footprints:C_0402_1005Metric"
		(layer "B.Cu")
		(at 224.15 141.53 90)
		(descr "Capacitor SMD 0402")
		(tags "capacitor SMD 0402")
		(property "Reference" "C81"
			(at 0.58 0.4 90)
			(layer "B.SilkS")
			(hide yes)
			(effects
				(font
					(size 0.7 0.7)
					(thickness 0.15)
				)
				(justify right bottom mirror)
			)
		)
		(property "Value" "C_100n_0402"
			(at -1.022927 -2.155213 90)
			(layer "B.Fab")
			(hide yes)
			(effects
				(font
					(size 0.7 0.7)
					(thickness 0.15)
				)
				(justify right bottom mirror)
			)
		)
		(property "Datasheet" "https://www.murata.com/products/productdetail?partno=GRM155R61H104KE14%23"
			(at 0 0 90)
			(layer "F.Fab")
			(hide yes)
			(effects
				(font
					(size 1.27 1.27)
					(thickness 0.15)
				)
			)
		)
		(property "Description" "SMD Multilayer Ceramic Capacitor, 0.1 µF, 50 V, 0402 [1005 Metric], ± 10%, X5R, GRM Series"
			(at 0 0 90)
			(layer "F.Fab")
			(hide yes)
			(effects
				(font
					(size 1.27 1.27)
					(thickness 0.15)
				)
			)
		)
		(property "Author" "Antmicro"
			(at 365.68 -82.62 0)
			(layer "B.Fab")
			(hide yes)
			(effects
				(font
					(size 1 1)
					(thickness 0.15)
				)
				(justify mirror)
			)
		)
		(property "Dielectric" "X5R"
			(at 365.68 -82.62 0)
			(layer "B.Fab")
			(hide yes)
			(effects
				(font
					(size 1 1)
					(thickness 0.15)
				)
				(justify mirror)
			)
		)
		(property "License" "Apache-2.0"
			(at 365.68 -82.62 0)
			(layer "B.Fab")
			(hide yes)
			(effects
				(font
					(size 1 1)
					(thickness 0.15)
				)
				(justify mirror)
			)
		)
		(property "MPN" "GRM155R61H104KE14D"
			(at 365.68 -82.62 0)
			(layer "B.Fab")
			(hide yes)
			(effects
				(font
					(size 1 1)
					(thickness 0.15)
				)
				(justify mirror)
			)
		)
		(property "Manufacturer" "Murata"
			(at 365.68 -82.62 0)
			(layer "B.Fab")
			(hide yes)
			(effects
				(font
					(size 1 1)
					(thickness 0.15)
				)
				(justify mirror)
			)
		)
		(property "Public" ""
			(at 365.68 -82.62 0)
			(layer "B.Fab")
			(hide yes)
			(effects
				(font
					(size 1 1)
					(thickness 0.15)
				)
				(justify mirror)
			)
		)
		(property "Val" "100n"
			(at 365.68 -82.62 0)
			(layer "B.Fab")
			(hide yes)
			(effects
				(font
					(size 1 1)
					(thickness 0.15)
				)
				(justify mirror)
			)
		)
		(property "Voltage" "50V"
			(at 365.68 -82.62 0)
			(layer "B.Fab")
			(hide yes)
			(effects
				(font
					(size 1 1)
					(thickness 0.15)
				)
				(justify mirror)
			)
		)
		(sheetname "/FPGA GPIO/")
		(sheetfile "fpga-gpio.kicad_sch")
		(attr smd)
		(fp_rect
			(start -0.925 0.47)
			(end 0.925 -0.47)
			(stroke
				(width 0.05)
				(type default)
			)
			(fill no)
			(layer "B.CrtYd")
		)
		(fp_line
			(start 0.504 -0.248)
			(end -0.494 -0.248)
			(stroke
				(width 0.15)
				(type solid)
			)
			(layer "B.Fab")
		)
		(fp_line
			(start -0.494 -0.248)
			(end -0.494 0.25)
			(stroke
				(width 0.15)
				(type solid)
			)
			(layer "B.Fab")
		)
		(fp_line
			(start 0.504 0.25)
			(end 0.504 -0.248)
			(stroke
				(width 0.15)
				(type solid)
			)
			(layer "B.Fab")
		)
		(fp_line
			(start -0.494 0.25)
			(end 0.504 0.25)
			(stroke
				(width 0.15)
				(type solid)
			)
			(layer "B.Fab")
		)
		(fp_text user "81"
			(at 1.43 -0.025 90)
			(unlocked yes)
			(layer "B.SilkS")
			(effects
				(font
					(size 0.7 0.7)
					(thickness 0.15)
				)
				(justify mirror)
			)
		)
		(fp_text user "${REFERENCE}"
			(at -0.939 -4.599 270)
			(layer "B.Fab")
			(effects
				(font
					(size 0.7 0.7)
					(thickness 0.15)
				)
				(justify left bottom mirror)
			)
		)
		(fp_text user "License: Apache-2.0"
			(at -0.939 -5.799 270)
			(layer "B.Fab")
			(effects
				(font
					(size 0.7 0.7)
					(thickness 0.15)
				)
				(justify left bottom mirror)
			)
		)
		(fp_text user "Author: Antmicro"
			(at -0.939 -3.399 270)
			(layer "B.Fab")
			(effects
				(font
					(size 0.7 0.7)
					(thickness 0.15)
				)
				(justify left bottom mirror)
			)
		)
		(pad "1" smd roundrect
			(at -0.48 0 90)
			(size 0.59 0.64)
			(layers "B.Cu" "B.Mask" "B.Paste")
			(roundrect_rratio 0.25)
			(net 50 "+3V3")
			(pintype "passive")
		)
		(pad "2" smd roundrect
			(at 0.48 0 90)
			(size 0.59 0.64)
			(layers "B.Cu" "B.Mask" "B.Paste")
			(roundrect_rratio 0.25)
			(net 417 "GND")
			(pintype "passive")
		)
	)
	(footprint "antmicro-footprints:R_Array_4x0201_Panasonic_EXB18V"
		(layer "B.Cu")
		(at 206.993002 121.65 -90)
		(property "Reference" "R22"
			(at 1.13 0.743002 90)
			(layer "B.SilkS")
			(effects
				(font
					(size 0.7 0.7)
					(thickness 0.15)
				)
				(justify right bottom mirror)
			)
		)
		(property "Value" "R_4x0R_0201_array"
			(at -1.1 -1.8 90)
			(layer "B.Fab")
			(hide yes)
			(effects
				(font
					(size 0.7 0.7)
					(thickness 0.15)
				)
				(justify left bottom mirror)
			)
		)
		(property "Datasheet" "http://industrial.panasonic.com/cdbs/www-data/pdf/AOC0000/AOC0000C14.pdf"
			(at 0 0 270)
			(layer "F.Fab")
			(hide yes)
			(effects
				(font
					(size 1.27 1.27)
					(thickness 0.15)
				)
			)
		)
		(property "Description" "Zero Ohm Network Resistor, Jumper, 0201 [0603 Metric], Thick Film, Isolated, Flat, 4 Resistors"
			(at 0 0 270)
			(layer "F.Fab")
			(hide yes)
			(effects
				(font
					(size 1.27 1.27)
					(thickness 0.15)
				)
			)
		)
		(property "Author" "Antmicro"
			(at 85.343002 328.643002 0)
			(layer "B.Fab")
			(hide yes)
			(effects
				(font
					(size 1 1)
					(thickness 0.15)
				)
				(justify mirror)
			)
		)
		(property "License" "Apache-2.0"
			(at 85.343002 328.643002 0)
			(layer "B.Fab")
			(hide yes)
			(effects
				(font
					(size 1 1)
					(thickness 0.15)
				)
				(justify mirror)
			)
		)
		(property "MPN" "EXB-18VR000X"
			(at 85.343002 328.643002 0)
			(layer "B.Fab")
			(hide yes)
			(effects
				(font
					(size 1 1)
					(thickness 0.15)
				)
				(justify mirror)
			)
		)
		(property "Manufacturer" "Panasonic"
			(at 85.343002 328.643002 0)
			(layer "B.Fab")
			(hide yes)
			(effects
				(font
					(size 1 1)
					(thickness 0.15)
				)
				(justify mirror)
			)
		)
		(property "Val" "4x0R_0201"
			(at 85.343002 328.643002 0)
			(layer "B.Fab")
			(hide yes)
			(effects
				(font
					(size 1 1)
					(thickness 0.15)
				)
				(justify mirror)
			)
		)
		(sheetname "/FPGA MSSIO/")
		(sheetfile "fpga-mssio.kicad_sch")
		(attr smd)
		(fp_line
			(start -0.8 0.45)
			(end -0.8 -0.45)
			(stroke
				(width 0.12)
				(type solid)
			)
			(layer "B.SilkS")
		)
		(fp_line
			(start 0.8 0.45)
			(end 0.8 -0.45)
			(stroke
				(width 0.12)
				(type solid)
			)
			(layer "B.SilkS")
		)
		(fp_rect
			(start -0.898 0.66)
			(end 0.898 -0.65)
			(stroke
				(width 0.05)
				(type solid)
			)
			(fill no)
			(layer "B.CrtYd")
		)
		(fp_text user "${REFERENCE}"
			(at -1.051 -3.2 90)
			(layer "B.Fab")
			(effects
				(font
					(size 0.7 0.7)
					(thickness 0.15)
				)
				(justify left bottom mirror)
			)
		)
		(fp_text user "License: Apache-2.0"
			(at -1.051 -6 90)
			(layer "B.Fab")
			(effects
				(font
					(size 0.7 0.7)
					(thickness 0.15)
				)
				(justify left bottom mirror)
			)
		)
		(fp_text user "Author: Antmicro"
			(at -1.051 -4.599 90)
			(layer "B.Fab")
			(effects
				(font
					(size 0.7 0.7)
					(thickness 0.15)
				)
				(justify left bottom mirror)
			)
		)
		(pad "1" smd roundrect
			(at -0.6 -0.298 270)
			(size 0.2 0.4)
			(layers "B.Cu" "B.Mask" "B.Paste")
			(roundrect_rratio 0.25)
			(net 207 "/FPGA MSSIO/EMMC.DAT3")
			(pinfunction "R1.1")
			(pintype "passive")
		)
		(pad "2" smd roundrect
			(at -0.202 -0.298 270)
			(size 0.2 0.4)
			(layers "B.Cu" "B.Mask" "B.Paste")
			(roundrect_rratio 0.25)
			(net 208 "/FPGA MSSIO/EMMC.DAT0")
			(pinfunction "R2.1")
			(pintype "passive")
		)
		(pad "3" smd roundrect
			(at 0.2 -0.298 270)
			(size 0.2 0.4)
			(layers "B.Cu" "B.Mask" "B.Paste")
			(roundrect_rratio 0.25)
			(net 213 "/FPGA MSSIO/EMMC.DAT5")
			(pinfunction "R3.1")
			(pintype "passive")
		)
		(pad "4" smd roundrect
			(at 0.598 -0.298 270)
			(size 0.2 0.4)
			(layers "B.Cu" "B.Mask" "B.Paste")
			(roundrect_rratio 0.25)
			(net 214 "/FPGA MSSIO/EMMC.DAT7")
			(pinfunction "R4.1")
			(pintype "passive")
		)
		(pad "5" smd roundrect
			(at 0.598 0.3 270)
			(size 0.2 0.4)
			(layers "B.Cu" "B.Mask" "B.Paste")
			(roundrect_rratio 0.25)
			(net 215 "/FPGA MSSIO/MEM.DAT7")
			(pinfunction "R4.2")
			(pintype "passive")
		)
		(pad "6" smd roundrect
			(at 0.2 0.3 270)
			(size 0.2 0.4)
			(layers "B.Cu" "B.Mask" "B.Paste")
			(roundrect_rratio 0.25)
			(net 216 "/FPGA MSSIO/MEM.DAT5")
			(pinfunction "R3.2")
			(pintype "passive")
		)
		(pad "7" smd roundrect
			(at -0.202 0.3 270)
			(size 0.2 0.4)
			(layers "B.Cu" "B.Mask" "B.Paste")
			(roundrect_rratio 0.25)
			(net 235 "/FPGA MSSIO/MEM.DAT0")
			(pinfunction "R2.2")
			(pintype "passive")
		)
		(pad "8" smd roundrect
			(at -0.6 0.3 270)
			(size 0.2 0.4)
			(layers "B.Cu" "B.Mask" "B.Paste")
			(roundrect_rratio 0.25)
			(net 236 "/FPGA MSSIO/MEM.DAT3")
			(pinfunction "R1.2")
			(pintype "passive")
		)
	)
)
